# T6G (Grand Teton) — schematic netlist excerpt (pin names and nets, part order shuffled) for the footprints in the layout excerpt that follows; sources: Cadence DE-HDL packaged netlist, KiCad conversion of 04192023_DAF0TMB3IC0_F0TG_MB_C_brd_V02_OCP.brd

C6718  Q_CAP_DIFFBUS  DIFF BUS_0.22UF 6.3V 20% X6S  pkg C0201  page 341 : \1\ = P5E_CPU1_P2_TX_BUF_C_DN<12> ; \2\ = P5E_CPU1_P2_TX_BUF_DN<12>
R4148  Q_RES  33.2 1% CHIP  pkg 0402LF  page 81 : A = GPU_3V3IO_RSVD5_FFU_ISO_R ; B = GPU_3V3IO_RSVD5_FFU_ISO
R663  Q_RES  1K 1% CHIP  pkg 0402LF  page 364 : A = P3V3_AUX ; B = P0V9_RETIMER_CPU1_CFP

(kicad_pcb
	(version 20260206)
	(generator "pcbnew")
	(generator_version "10.0")
	(general
		(thickness 1.6)
		(legacy_teardrops no)
	)
	(paper "A4")
	(title_block
		(title "04192023_DAF0TMB3IC0_F0TG_MB_C_brd_V02_OCP.brd")
		(comment 1 "Grand Teton / footprints 2332-2334 of 8354")
	)
	(layers
		(0 "F.Cu" signal "TOP")
		(4 "In1.Cu" signal "GND")
		(6 "In2.Cu" signal "IN1")
		(8 "In3.Cu" signal "GND1")
		(10 "In4.Cu" signal "IN2")
		(12 "In5.Cu" signal "GND2")
		(14 "In6.Cu" signal "IN3")
		(16 "In7.Cu" signal "GND3")
		(18 "In8.Cu" signal "VCC")
		(20 "In9.Cu" signal "VCC1")
		(22 "In10.Cu" signal "GND4")
		(24 "In11.Cu" signal "IN4")
		(26 "In12.Cu" signal "GND5")
		(28 "In13.Cu" signal "IN5")
		(30 "In14.Cu" signal "GND6")
		(32 "In15.Cu" signal "IN6")
		(34 "In16.Cu" signal "GND7")
		(2 "B.Cu" signal "BOTTOM")
		(9 "F.Adhes" user "F.Adhesive")
		(11 "B.Adhes" user "B.Adhesive")
		(13 "F.Paste" user "Package Geometry/Pastemask Top")
		(15 "B.Paste" user "Package Geometry/Pastemask Bottom")
		(5 "F.SilkS" user "Ref Des/Silkscreen Top")
		(7 "B.SilkS" user "Ref Des/Silkscreen Bottom")
		(1 "F.Mask" user "Board Geometry/Soldermask Top")
		(3 "B.Mask" user "Board Geometry/Soldermask Bottom")
		(17 "Dwgs.User" user "User.Drawings")
		(19 "Cmts.User" user "User.Comments")
		(21 "Eco1.User" user "User.Eco1")
		(23 "Eco2.User" user "User.Eco2")
		(25 "Edge.Cuts" user "Board Geometry/Outline")
		(27 "Margin" user)
		(31 "F.CrtYd" user "Package Geometry/Place Bound Top")
		(29 "B.CrtYd" user "Package Geometry/Place Bound Bottom")
		(35 "F.Fab" user "Ref Des/Assembly Top")
		(33 "B.Fab" user "Ref Des/Assembly Bottom")
	)
	(footprint ""
		(layer "F.Cu")
		(at 10.066782 -413.231584)
		(property "Reference" "R663"
			(at 0 0 0)
			(layer "F.SilkS")
			(hide yes)
			(effects
				(font
					(size 1.27 1.27)
				)
			)
		)
		(property "Value" ""
			(at 0 0 0)
			(layer "F.Fab")
			(effects
				(font
					(size 1.27 1.27)
				)
			)
		)
		(duplicate_pad_numbers_are_jumpers no)
		(fp_line
			(start -0.7874 -0.4064)
			(end 0.7874 -0.4064)
			(stroke
				(width 0.1524)
				(type default)
			)
			(layer "F.SilkS")
		)
		(fp_line
			(start -0.7874 0.4064)
			(end -0.7874 -0.4064)
			(stroke
				(width 0.1524)
				(type default)
			)
			(layer "F.SilkS")
		)
		(fp_line
			(start 0.7874 -0.4064)
			(end 0.7874 0.4064)
			(stroke
				(width 0.1524)
				(type default)
			)
			(layer "F.SilkS")
		)
		(fp_line
			(start 0.7874 0.4064)
			(end -0.7874 0.4064)
			(stroke
				(width 0.1524)
				(type default)
			)
			(layer "F.SilkS")
		)
		(fp_line
			(start -0.67945 -0.305054)
			(end -0.12065 -0.305054)
			(stroke
				(width 0.1)
				(type default)
			)
			(layer "F.Fab")
		)
		(fp_line
			(start -0.67945 0.3048)
			(end -0.67945 -0.305054)
			(stroke
				(width 0.1)
				(type default)
			)
			(layer "F.Fab")
		)
		(fp_line
			(start -0.12065 -0.305054)
			(end -0.12065 -0.2794)
			(stroke
				(width 0.1)
				(type default)
			)
			(layer "F.Fab")
		)
		(fp_line
			(start -0.12065 -0.2794)
			(end 0.12065 -0.2794)
			(stroke
				(width 0.1)
				(type default)
			)
			(layer "F.Fab")
		)
		(fp_line
			(start -0.12065 0.2794)
			(end -0.12065 0.3048)
			(stroke
				(width 0.1)
				(type default)
			)
			(layer "F.Fab")
		)
		(fp_line
			(start -0.12065 0.3048)
			(end -0.67945 0.3048)
			(stroke
				(width 0.1)
				(type default)
			)
			(layer "F.Fab")
		)
		(fp_line
			(start 0.120396 0.2794)
			(end -0.12065 0.2794)
			(stroke
				(width 0.1)
				(type default)
			)
			(layer "F.Fab")
		)
		(fp_line
			(start 0.120396 0.3048)
			(end 0.120396 0.2794)
			(stroke
				(width 0.1)
				(type default)
			)
			(layer "F.Fab")
		)
		(fp_line
			(start 0.12065 -0.3048)
			(end 0.67945 -0.3048)
			(stroke
				(width 0.1)
				(type default)
			)
			(layer "F.Fab")
		)
		(fp_line
			(start 0.12065 -0.2794)
			(end 0.12065 -0.3048)
			(stroke
				(width 0.1)
				(type default)
			)
			(layer "F.Fab")
		)
		(fp_line
			(start 0.67945 -0.3048)
			(end 0.67945 0.3048)
			(stroke
				(width 0.1)
				(type default)
			)
			(layer "F.Fab")
		)
		(fp_line
			(start 0.67945 0.3048)
			(end 0.120396 0.3048)
			(stroke
				(width 0.1)
				(type default)
			)
			(layer "F.Fab")
		)
		(pad "1" smd circle
			(at -0.40005 0)
			(size 0 0)
			(layers "F.Cu" "F.Mask" "F.Paste")
			(net "P3V3_AUX")
		)
		(pad "2" smd circle
			(at 0.40005 0)
			(size 0 0)
			(layers "F.Cu" "F.Mask" "F.Paste")
			(net "P0V9_RETIMER_CPU1_CFP")
		)
	)
	(footprint ""
		(layer "F.Cu")
		(at 200.952608 -117.689376)
		(property "Reference" "R4148"
			(at 0 0 0)
			(layer "F.SilkS")
			(hide yes)
			(effects
				(font
					(size 1.27 1.27)
				)
			)
		)
		(property "Value" ""
			(at 0 0 0)
			(layer "F.Fab")
			(effects
				(font
					(size 1.27 1.27)
				)
			)
		)
		(duplicate_pad_numbers_are_jumpers no)
		(fp_line
			(start -0.7874 -0.4064)
			(end 0.7874 -0.4064)
			(stroke
				(width 0.1524)
				(type default)
			)
			(layer "F.SilkS")
		)
		(fp_line
			(start -0.7874 0.4064)
			(end -0.7874 -0.4064)
			(stroke
				(width 0.1524)
				(type default)
			)
			(layer "F.SilkS")
		)
		(fp_line
			(start 0.7874 -0.4064)
			(end 0.7874 0.4064)
			(stroke
				(width 0.1524)
				(type default)
			)
			(layer "F.SilkS")
		)
		(fp_line
			(start 0.7874 0.4064)
			(end -0.7874 0.4064)
			(stroke
				(width 0.1524)
				(type default)
			)
			(layer "F.SilkS")
		)
		(fp_line
			(start -0.67945 -0.305054)
			(end -0.12065 -0.305054)
			(stroke
				(width 0.1)
				(type default)
			)
			(layer "F.Fab")
		)
		(fp_line
			(start -0.67945 0.3048)
			(end -0.67945 -0.305054)
			(stroke
				(width 0.1)
				(type default)
			)
			(layer "F.Fab")
		)
		(fp_line
			(start -0.12065 -0.305054)
			(end -0.12065 -0.2794)
			(stroke
				(width 0.1)
				(type default)
			)
			(layer "F.Fab")
		)
		(fp_line
			(start -0.12065 -0.2794)
			(end 0.12065 -0.2794)
			(stroke
				(width 0.1)
				(type default)
			)
			(layer "F.Fab")
		)
		(fp_line
			(start -0.12065 0.2794)
			(end -0.12065 0.3048)
			(stroke
				(width 0.1)
				(type default)
			)
			(layer "F.Fab")
		)
		(fp_line
			(start -0.12065 0.3048)
			(end -0.67945 0.3048)
			(stroke
				(width 0.1)
				(type default)
			)
			(layer "F.Fab")
		)
		(fp_line
			(start 0.120396 0.2794)
			(end -0.12065 0.2794)
			(stroke
				(width 0.1)
				(type default)
			)
			(layer "F.Fab")
		)
		(fp_line
			(start 0.120396 0.3048)
			(end 0.120396 0.2794)
			(stroke
				(width 0.1)
				(type default)
			)
			(layer "F.Fab")
		)
		(fp_line
			(start 0.12065 -0.3048)
			(end 0.67945 -0.3048)
			(stroke
				(width 0.1)
				(type default)
			)
			(layer "F.Fab")
		)
		(fp_line
			(start 0.12065 -0.2794)
			(end 0.12065 -0.3048)
			(stroke
				(width 0.1)
				(type default)
			)
			(layer "F.Fab")
		)
		(fp_line
			(start 0.67945 -0.3048)
			(end 0.67945 0.3048)
			(stroke
				(width 0.1)
				(type default)
			)
			(layer "F.Fab")
		)
		(fp_line
			(start 0.67945 0.3048)
			(end 0.120396 0.3048)
			(stroke
				(width 0.1)
				(type default)
			)
			(layer "F.Fab")
		)
		(pad "1" smd circle
			(at -0.40005 0)
			(size 0 0)
			(layers "F.Cu" "F.Mask" "F.Paste")
			(net "GPU_3V3IO_RSVD5_FFU_ISO_R")
		)
		(pad "2" smd circle
			(at 0.40005 0)
			(size 0 0)
			(layers "F.Cu" "F.Mask" "F.Paste")
			(net "GPU_3V3IO_RSVD5_FFU_ISO")
		)
	)
	(footprint ""
		(layer "F.Cu")
		(at 151.627586 -408.517344 -90)
		(property "Reference" "C6718"
			(at 0 0 270)
			(layer "F.SilkS")
			(hide yes)
			(effects
				(font
					(size 1.27 1.27)
				)
			)
		)
		(property "Value" ""
			(at 0 0 270)
			(layer "F.Fab")
			(effects
				(font
					(size 1.27 1.27)
				)
			)
		)
		(duplicate_pad_numbers_are_jumpers no)
		(fp_line
			(start -0.299974 0.150114)
			(end -0.299974 -0.150114)
			(stroke
				(width 0.1)
				(type default)
			)
			(layer "F.Fab")
		)
		(fp_line
			(start 0.299974 0.150114)
			(end -0.299974 0.150114)
			(stroke
				(width 0.1)
				(type default)
			)
			(layer "F.Fab")
		)
		(fp_line
			(start -0.299974 -0.150114)
			(end 0.299974 -0.150114)
			(stroke
				(width 0.1)
				(type default)
			)
			(layer "F.Fab")
		)
		(fp_line
			(start 0.299974 -0.150114)
			(end 0.299974 0.150114)
			(stroke
				(width 0.1)
				(type default)
			)
			(layer "F.Fab")
		)
		(pad "1" smd rect
			(at -0.2667 0 270)
			(size 0.3048 0.381)
			(layers "F.Cu" "F.Mask" "F.Paste")
			(net "P5E_CPU1_P2_TX_BUF_C_DN<12>")
		)
		(pad "2" smd rect
			(at 0.2667 0 270)
			(size 0.3048 0.381)
			(layers "F.Cu" "F.Mask" "F.Paste")
			(net "P5E_CPU1_P2_TX_BUF_DN<12>")
		)
	)
)
